(kicad_pcb
	(version 20260206)
	(generator "pcbnew")
	(generator_version "10.0")
	(general
		(thickness 1.6)
		(legacy_teardrops no)
	)
	(paper "A4")
	(title_block
		(title "Bryce Canyon_IOM_IOC_16318-2_OCP.brd")
		(comment 1 "Bryce Canyon / footprints 1436-1443 of 1605")
	)
	(layers
		(0 "F.Cu" signal "TOP")
		(4 "In1.Cu" signal "L2GND")
		(6 "In2.Cu" signal "L3")
		(8 "In3.Cu" signal "L4VCC")
		(10 "In4.Cu" signal "L5VCC")
		(12 "In5.Cu" signal "L6")
		(14 "In6.Cu" signal "L7GND")
		(2 "B.Cu" signal "BOTTOM")
		(9 "F.Adhes" user "F.Adhesive")
		(11 "B.Adhes" user "B.Adhesive")
		(13 "F.Paste" user "Package Geometry/Pastemask Top")
		(15 "B.Paste" user "Package Geometry/Pastemask Bottom")
		(5 "F.SilkS" user "Ref Des/Silkscreen Top")
		(7 "B.SilkS" user "Ref Des/Silkscreen Bottom")
		(1 "F.Mask" user "Board Geometry/Soldermask Top")
		(3 "B.Mask" user "Board Geometry/Soldermask Bottom")
		(17 "Dwgs.User" user "User.Drawings")
		(19 "Cmts.User" user "User.Comments")
		(21 "Eco1.User" user "User.Eco1")
		(23 "Eco2.User" user "User.Eco2")
		(25 "Edge.Cuts" user "Board Geometry/Outline")
		(27 "Margin" user)
		(31 "F.CrtYd" user "Package Geometry/Place Bound Top")
		(29 "B.CrtYd" user "Package Geometry/Place Bound Bottom")
		(35 "F.Fab" user "Ref Des/Assembly Top")
		(33 "B.Fab" user "Ref Des/Assembly Bottom")
	)
	(footprint ""
		(layer "B.Cu")
		(at 67.7672 -145.6436 180)
		(property "Reference" "R159"
			(at 0 0 0)
			(layer "B.SilkS")
			(hide yes)
			(effects
				(font
					(size 1.27 1.27)
				)
				(justify mirror)
			)
		)
		(property "Value" "0R2J-2-GP"
			(at -0.064008 -3.993896 180)
			(unlocked yes)
			(layer "B.Fab")
			(hide yes)
			(effects
				(font
					(size 1.016 1.016)
					(thickness 0.1524)
				)
				(justify mirror)
			)
		)
		(property "Device Type" "R402H16"
			(at -0.064008 -5.517896 180)
			(unlocked yes)
			(layer "B.Fab")
			(hide yes)
			(effects
				(font
					(size 1.016 1.016)
					(thickness 0.1524)
				)
				(justify mirror)
			)
		)
		(duplicate_pad_numbers_are_jumpers no)
		(fp_line
			(start 0.508 -0.9398)
			(end 0.508 0.9398)
			(stroke
				(width 0.1524)
				(type default)
			)
			(layer "B.SilkS")
		)
		(fp_line
			(start -0.508 -0.9398)
			(end 0.508 -0.9398)
			(stroke
				(width 0.1524)
				(type default)
			)
			(layer "B.SilkS")
		)
		(fp_rect
			(start 0.508 0.9398)
			(end -0.508 -0.9398)
			(stroke
				(width 0)
				(type default)
			)
			(fill no)
			(layer "B.CrtYd")
		)
		(fp_rect
			(start 0.508 0.9398)
			(end -0.508 -0.9398)
			(stroke
				(width 0)
				(type default)
			)
			(fill no)
			(layer "B.Fab")
		)
		(pad "1" smd custom
			(at 0 -0.4445)
			(size 0.1397 0.1397)
			(layers "B.Cu" "B.Mask" "B.Paste")
			(net "BMC_SMB12_CLK")
			(options
				(clearance outline)
				(anchor circle)
			)
			(primitives
				(gr_poly
					(pts
						(arc
							(start -0.1778 0.2794)
							(mid -0.249642 0.249642)
							(end -0.2794 0.1778)
						)
						(arc
							(start -0.2794 -0.1778)
							(mid -0.249642 -0.249642)
							(end -0.1778 -0.2794)
						)
						(arc
							(start 0.1778 -0.2794)
							(mid 0.249642 -0.249642)
							(end 0.2794 -0.1778)
						)
						(arc
							(start 0.2794 0.1778)
							(mid 0.249642 0.249642)
							(end 0.1778 0.2794)
						)
					)
					(width 0)
					(fill yes)
				)
			)
		)
		(pad "2" smd custom
			(at 0 0.4445)
			(size 0.1397 0.1397)
			(layers "B.Cu" "B.Mask" "B.Paste")
			(net "I2C_DEBUG_SCL_L")
			(options
				(clearance outline)
				(anchor circle)
			)
			(primitives
				(gr_poly
					(pts
						(arc
							(start -0.1778 0.2794)
							(mid -0.249642 0.249642)
							(end -0.2794 0.1778)
						)
						(arc
							(start -0.2794 -0.1778)
							(mid -0.249642 -0.249642)
							(end -0.1778 -0.2794)
						)
						(arc
							(start 0.1778 -0.2794)
							(mid 0.249642 -0.249642)
							(end 0.2794 -0.1778)
						)
						(arc
							(start 0.2794 0.1778)
							(mid 0.249642 0.249642)
							(end 0.1778 0.2794)
						)
					)
					(width 0)
					(fill yes)
				)
			)
		)
	)
	(footprint ""
		(layer "B.Cu")
		(at 179.577238 -71.92137)
		(property "Reference" "TP114"
			(at 0 0 0)
			(layer "B.SilkS")
			(hide yes)
			(effects
				(font
					(size 1.27 1.27)
				)
				(justify mirror)
			)
		)
		(property "Value" "TPAD28-2-GP"
			(at 0.0127 -1.6637 0)
			(unlocked yes)
			(layer "B.Fab")
			(hide yes)
			(effects
				(font
					(size 1.016 1.016)
					(thickness 0.1524)
				)
				(justify mirror)
			)
		)
		(property "Device Type" "TPAD28"
			(at 0.0127 -3.1877 0)
			(unlocked yes)
			(layer "B.Fab")
			(hide yes)
			(effects
				(font
					(size 1.016 1.016)
					(thickness 0.1524)
				)
				(justify mirror)
			)
		)
		(duplicate_pad_numbers_are_jumpers no)
		(fp_poly
			(pts
				(arc
					(start 0.3556 0)
					(mid -0.3556 0)
					(end 0.3556 0)
				)
			)
			(stroke
				(width 0)
				(type default)
			)
			(fill no)
			(layer "B.CrtYd")
		)
		(fp_poly
			(pts
				(arc
					(start 0.6096 0)
					(mid -0.6096 0)
					(end 0.6096 0)
				)
			)
			(stroke
				(width 0)
				(type default)
			)
			(fill no)
			(layer "B.Fab")
		)
		(pad "1" smd circle
			(at 0 0 180)
			(size 0.7112 0.7112)
			(layers "B.Cu" "B.Mask" "B.Paste")
			(net "IOC_GPIO_27")
		)
	)
	(footprint ""
		(layer "B.Cu")
		(at 89.52992 -149.317456)
		(property "Reference" "R40"
			(at 0 0 0)
			(layer "B.SilkS")
			(hide yes)
			(effects
				(font
					(size 1.27 1.27)
				)
				(justify mirror)
			)
		)
		(property "Value" "4K7R2F-GP"
			(at -0.064008 -3.993896 0)
			(unlocked yes)
			(layer "B.Fab")
			(hide yes)
			(effects
				(font
					(size 1.016 1.016)
					(thickness 0.1524)
				)
				(justify mirror)
			)
		)
		(property "Device Type" "R402H16"
			(at -0.064008 -5.517896 0)
			(unlocked yes)
			(layer "B.Fab")
			(hide yes)
			(effects
				(font
					(size 1.016 1.016)
					(thickness 0.1524)
				)
				(justify mirror)
			)
		)
		(duplicate_pad_numbers_are_jumpers no)
		(fp_line
			(start -0.508 -0.9398)
			(end 0.508 -0.9398)
			(stroke
				(width 0.1524)
				(type default)
			)
			(layer "B.SilkS")
		)
		(fp_line
			(start 0.508 -0.9398)
			(end 0.508 0.9398)
			(stroke
				(width 0.1524)
				(type default)
			)
			(layer "B.SilkS")
		)
		(fp_rect
			(start 0.508 0.9398)
			(end -0.508 -0.9398)
			(stroke
				(width 0)
				(type default)
			)
			(fill no)
			(layer "B.CrtYd")
		)
		(fp_rect
			(start 0.508 0.9398)
			(end -0.508 -0.9398)
			(stroke
				(width 0)
				(type default)
			)
			(fill no)
			(layer "B.Fab")
		)
		(pad "1" smd custom
			(at 0 -0.4445 180)
			(size 0.1397 0.1397)
			(layers "B.Cu" "B.Mask" "B.Paste")
			(net "USB_EN_1")
			(options
				(clearance outline)
				(anchor circle)
			)
			(primitives
				(gr_poly
					(pts
						(arc
							(start -0.1778 0.2794)
							(mid -0.249642 0.249642)
							(end -0.2794 0.1778)
						)
						(arc
							(start -0.2794 -0.1778)
							(mid -0.249642 -0.249642)
							(end -0.1778 -0.2794)
						)
						(arc
							(start 0.1778 -0.2794)
							(mid 0.249642 -0.249642)
							(end 0.2794 -0.1778)
						)
						(arc
							(start 0.2794 0.1778)
							(mid 0.249642 0.249642)
							(end 0.1778 0.2794)
						)
					)
					(width 0)
					(fill yes)
				)
			)
		)
		(pad "2" smd custom
			(at 0 0.4445 180)
			(size 0.1397 0.1397)
			(layers "B.Cu" "B.Mask" "B.Paste")
			(net "GND")
			(options
				(clearance outline)
				(anchor circle)
			)
			(primitives
				(gr_poly
					(pts
						(arc
							(start -0.1778 0.2794)
							(mid -0.249642 0.249642)
							(end -0.2794 0.1778)
						)
						(arc
							(start -0.2794 -0.1778)
							(mid -0.249642 -0.249642)
							(end -0.1778 -0.2794)
						)
						(arc
							(start 0.1778 -0.2794)
							(mid 0.249642 -0.249642)
							(end 0.2794 -0.1778)
						)
						(arc
							(start 0.2794 0.1778)
							(mid 0.249642 0.249642)
							(end 0.1778 0.2794)
						)
					)
					(width 0)
					(fill yes)
				)
			)
		)
	)
	(footprint ""
		(layer "B.Cu")
		(at 170.2308 -51.2064 180)
		(property "Reference" "R678"
			(at 0 0 0)
			(layer "B.SilkS")
			(hide yes)
			(effects
				(font
					(size 1.27 1.27)
				)
				(justify mirror)
			)
		)
		(property "Value" "10KR2F-2-GP"
			(at -0.064008 -3.993896 180)
			(unlocked yes)
			(layer "B.Fab")
			(hide yes)
			(effects
				(font
					(size 1.016 1.016)
					(thickness 0.1524)
				)
				(justify mirror)
			)
		)
		(property "Device Type" "R402H16"
			(at -0.064008 -5.517896 180)
			(unlocked yes)
			(layer "B.Fab")
			(hide yes)
			(effects
				(font
					(size 1.016 1.016)
					(thickness 0.1524)
				)
				(justify mirror)
			)
		)
		(duplicate_pad_numbers_are_jumpers no)
		(fp_line
			(start 0.508 -0.9398)
			(end 0.508 0.9398)
			(stroke
				(width 0.1524)
				(type default)
			)
			(layer "B.SilkS")
		)
		(fp_line
			(start -0.508 -0.9398)
			(end 0.508 -0.9398)
			(stroke
				(width 0.1524)
				(type default)
			)
			(layer "B.SilkS")
		)
		(fp_rect
			(start 0.508 0.9398)
			(end -0.508 -0.9398)
			(stroke
				(width 0)
				(type default)
			)
			(fill no)
			(layer "B.CrtYd")
		)
		(fp_rect
			(start 0.508 0.9398)
			(end -0.508 -0.9398)
			(stroke
				(width 0)
				(type default)
			)
			(fill no)
			(layer "B.Fab")
		)
		(pad "1" smd custom
			(at 0 -0.4445)
			(size 0.1397 0.1397)
			(layers "B.Cu" "B.Mask" "B.Paste")
			(net "P1V8")
			(options
				(clearance outline)
				(anchor circle)
			)
			(primitives
				(gr_poly
					(pts
						(arc
							(start -0.1778 0.2794)
							(mid -0.249642 0.249642)
							(end -0.2794 0.1778)
						)
						(arc
							(start -0.2794 -0.1778)
							(mid -0.249642 -0.249642)
							(end -0.1778 -0.2794)
						)
						(arc
							(start 0.1778 -0.2794)
							(mid 0.249642 -0.249642)
							(end 0.2794 -0.1778)
						)
						(arc
							(start 0.2794 0.1778)
							(mid 0.249642 0.249642)
							(end 0.1778 0.2794)
						)
					)
					(width 0)
					(fill yes)
				)
			)
		)
		(pad "2" smd custom
			(at 0 0.4445)
			(size 0.1397 0.1397)
			(layers "B.Cu" "B.Mask" "B.Paste")
			(net "XM_NOR_CS_N")
			(options
				(clearance outline)
				(anchor circle)
			)
			(primitives
				(gr_poly
					(pts
						(arc
							(start -0.1778 0.2794)
							(mid -0.249642 0.249642)
							(end -0.2794 0.1778)
						)
						(arc
							(start -0.2794 -0.1778)
							(mid -0.249642 -0.249642)
							(end -0.1778 -0.2794)
						)
						(arc
							(start 0.1778 -0.2794)
							(mid 0.249642 -0.249642)
							(end 0.2794 -0.1778)
						)
						(arc
							(start 0.2794 0.1778)
							(mid 0.249642 0.249642)
							(end 0.1778 0.2794)
						)
					)
					(width 0)
					(fill yes)
				)
			)
		)
	)
	(footprint ""
		(layer "B.Cu")
		(at 206.4258 -65.4812 -90)
		(property "Reference" "R625"
			(at 0 0 90)
			(layer "B.SilkS")
			(hide yes)
			(effects
				(font
					(size 1.27 1.27)
				)
				(justify mirror)
			)
		)
		(property "Value" "3KR2J-2-GP"
			(at -0.064008 -3.993896 270)
			(unlocked yes)
			(layer "B.Fab")
			(hide yes)
			(effects
				(font
					(size 1.016 1.016)
					(thickness 0.1524)
				)
				(justify mirror)
			)
		)
		(property "Device Type" "R402H16"
			(at -0.064008 -5.517896 270)
			(unlocked yes)
			(layer "B.Fab")
			(hide yes)
			(effects
				(font
					(size 1.016 1.016)
					(thickness 0.1524)
				)
				(justify mirror)
			)
		)
		(duplicate_pad_numbers_are_jumpers no)
		(fp_line
			(start -0.508 -0.9398)
			(end 0.508 -0.9398)
			(stroke
				(width 0.1524)
				(type default)
			)
			(layer "B.SilkS")
		)
		(fp_line
			(start 0.508 -0.9398)
			(end 0.508 0.9398)
			(stroke
				(width 0.1524)
				(type default)
			)
			(layer "B.SilkS")
		)
		(fp_rect
			(start 0.508 0.9398)
			(end -0.508 -0.9398)
			(stroke
				(width 0)
				(type default)
			)
			(fill no)
			(layer "B.CrtYd")
		)
		(fp_rect
			(start 0.508 0.9398)
			(end -0.508 -0.9398)
			(stroke
				(width 0)
				(type default)
			)
			(fill no)
			(layer "B.Fab")
		)
		(pad "1" smd custom
			(at 0 -0.4445 90)
			(size 0.1397 0.1397)
			(layers "B.Cu" "B.Mask" "B.Paste")
			(net "RTRIM")
			(options
				(clearance outline)
				(anchor circle)
			)
			(primitives
				(gr_poly
					(pts
						(arc
							(start -0.1778 0.2794)
							(mid -0.249642 0.249642)
							(end -0.2794 0.1778)
						)
						(arc
							(start -0.2794 -0.1778)
							(mid -0.249642 -0.249642)
							(end -0.1778 -0.2794)
						)
						(arc
							(start 0.1778 -0.2794)
							(mid 0.249642 -0.249642)
							(end 0.2794 -0.1778)
						)
						(arc
							(start 0.2794 0.1778)
							(mid 0.249642 0.249642)
							(end 0.1778 0.2794)
						)
					)
					(width 0)
					(fill yes)
				)
			)
		)
		(pad "2" smd custom
			(at 0 0.4445 90)
			(size 0.1397 0.1397)
			(layers "B.Cu" "B.Mask" "B.Paste")
			(net "RTRIM#")
			(options
				(clearance outline)
				(anchor circle)
			)
			(primitives
				(gr_poly
					(pts
						(arc
							(start -0.1778 0.2794)
							(mid -0.249642 0.249642)
							(end -0.2794 0.1778)
						)
						(arc
							(start -0.2794 -0.1778)
							(mid -0.249642 -0.249642)
							(end -0.1778 -0.2794)
						)
						(arc
							(start 0.1778 -0.2794)
							(mid 0.249642 -0.249642)
							(end 0.2794 -0.1778)
						)
						(arc
							(start 0.2794 0.1778)
							(mid 0.249642 0.249642)
							(end 0.1778 0.2794)
						)
					)
					(width 0)
					(fill yes)
				)
			)
		)
	)
	(footprint ""
		(layer "B.Cu")
		(at 156.206444 -93.286834 -90)
		(property "Reference" "R616"
			(at 0 0 90)
			(layer "B.SilkS")
			(hide yes)
			(effects
				(font
					(size 1.27 1.27)
				)
				(justify mirror)
			)
		)
		(property "Value" "4K7R2F-GP"
			(at -0.064008 -3.993896 270)
			(unlocked yes)
			(layer "B.Fab")
			(hide yes)
			(effects
				(font
					(size 1.016 1.016)
					(thickness 0.1524)
				)
				(justify mirror)
			)
		)
		(property "Device Type" "R402H16"
			(at -0.064008 -5.517896 270)
			(unlocked yes)
			(layer "B.Fab")
			(hide yes)
			(effects
				(font
					(size 1.016 1.016)
					(thickness 0.1524)
				)
				(justify mirror)
			)
		)
		(duplicate_pad_numbers_are_jumpers no)
		(fp_line
			(start -0.508 -0.9398)
			(end 0.508 -0.9398)
			(stroke
				(width 0.1524)
				(type default)
			)
			(layer "B.SilkS")
		)
		(fp_line
			(start 0.508 -0.9398)
			(end 0.508 0.9398)
			(stroke
				(width 0.1524)
				(type default)
			)
			(layer "B.SilkS")
		)
		(fp_rect
			(start 0.508 0.9398)
			(end -0.508 -0.9398)
			(stroke
				(width 0)
				(type default)
			)
			(fill no)
			(layer "B.CrtYd")
		)
		(fp_rect
			(start 0.508 0.9398)
			(end -0.508 -0.9398)
			(stroke
				(width 0)
				(type default)
			)
			(fill no)
			(layer "B.Fab")
		)
		(pad "1" smd custom
			(at 0 -0.4445 90)
			(size 0.1397 0.1397)
			(layers "B.Cu" "B.Mask" "B.Paste")
			(net "P1V8")
			(options
				(clearance outline)
				(anchor circle)
			)
			(primitives
				(gr_poly
					(pts
						(arc
							(start -0.1778 0.2794)
							(mid -0.249642 0.249642)
							(end -0.2794 0.1778)
						)
						(arc
							(start -0.2794 -0.1778)
							(mid -0.249642 -0.249642)
							(end -0.1778 -0.2794)
						)
						(arc
							(start 0.1778 -0.2794)
							(mid 0.249642 -0.249642)
							(end 0.2794 -0.1778)
						)
						(arc
							(start 0.2794 0.1778)
							(mid 0.249642 0.249642)
							(end 0.1778 0.2794)
						)
					)
					(width 0)
					(fill yes)
				)
			)
		)
		(pad "2" smd custom
			(at 0 0.4445 90)
			(size 0.1397 0.1397)
			(layers "B.Cu" "B.Mask" "B.Paste")
			(net "IOC_RESET#")
			(options
				(clearance outline)
				(anchor circle)
			)
			(primitives
				(gr_poly
					(pts
						(arc
							(start -0.1778 0.2794)
							(mid -0.249642 0.249642)
							(end -0.2794 0.1778)
						)
						(arc
							(start -0.2794 -0.1778)
							(mid -0.249642 -0.249642)
							(end -0.1778 -0.2794)
						)
						(arc
							(start 0.1778 -0.2794)
							(mid 0.249642 -0.249642)
							(end 0.2794 -0.1778)
						)
						(arc
							(start 0.2794 0.1778)
							(mid 0.249642 0.249642)
							(end 0.1778 0.2794)
						)
					)
					(width 0)
					(fill yes)
				)
			)
		)
	)
	(footprint ""
		(layer "B.Cu")
		(at 197.5612 -49.784 -90)
		(property "Reference" "C347"
			(at 0 0 90)
			(layer "B.SilkS")
			(hide yes)
			(effects
				(font
					(size 1.27 1.27)
				)
				(justify mirror)
			)
		)
		(property "Value" "SC10U6D3V5KX-4GP"
			(at 0.0762 -6.1214 270)
			(unlocked yes)
			(layer "B.Fab")
			(hide yes)
			(effects
				(font
					(size 1.016 1.016)
					(thickness 0.1524)
				)
				(justify mirror)
			)
		)
		(property "Device Type" "C805H58"
			(at 0.0762 -8.1534 270)
			(unlocked yes)
			(layer "B.Fab")
			(hide yes)
			(effects
				(font
					(size 1.016 1.016)
					(thickness 0.1524)
				)
				(justify mirror)
			)
		)
		(duplicate_pad_numbers_are_jumpers no)
		(fp_line
			(start -0.635 0)
			(end 0.635 0)
			(stroke
				(width 0.508)
				(type default)
			)
			(layer "B.SilkS")
		)
		(fp_rect
			(start 0.9652 1.778)
			(end -0.9652 -1.778)
			(stroke
				(width 0)
				(type default)
			)
			(fill no)
			(layer "B.CrtYd")
		)
		(fp_poly
			(pts
				(xy 0.9652 -1.778) (xy -0.9652 -1.778) (xy -0.9652 1.778) (xy 0.9652 1.778)
			)
			(stroke
				(width 0)
				(type default)
			)
			(fill no)
			(layer "B.Fab")
		)
		(pad "1" smd rect
			(at 0 -0.9652 90)
			(size 1.397 1.143)
			(layers "B.Cu" "B.Mask" "B.Paste")
			(net "VDDA_SAS_REF_CLK")
		)
		(pad "2" smd rect
			(at 0 0.9652 90)
			(size 1.397 1.143)
			(layers "B.Cu" "B.Mask" "B.Paste")
			(net "GND")
		)
	)
	(footprint ""
		(layer "B.Cu")
		(at 47.5742 -128.1938)
		(property "Reference" "R152"
			(at 0 0 0)
			(layer "B.SilkS")
			(hide yes)
			(effects
				(font
					(size 1.27 1.27)
				)
				(justify mirror)
			)
		)
		(property "Value" "0R2J-2-GP"
			(at -0.064008 -3.993896 0)
			(unlocked yes)
			(layer "B.Fab")
			(hide yes)
			(effects
				(font
					(size 1.016 1.016)
					(thickness 0.1524)
				)
				(justify mirror)
			)
		)
		(property "Device Type" "R402H16"
			(at -0.064008 -5.517896 0)
			(unlocked yes)
			(layer "B.Fab")
			(hide yes)
			(effects
				(font
					(size 1.016 1.016)
					(thickness 0.1524)
				)
				(justify mirror)
			)
		)
		(duplicate_pad_numbers_are_jumpers no)
		(fp_line
			(start -0.508 -0.9398)
			(end 0.508 -0.9398)
			(stroke
				(width 0.1524)
				(type default)
			)
			(layer "B.SilkS")
		)
		(fp_line
			(start 0.508 -0.9398)
			(end 0.508 0.9398)
			(stroke
				(width 0.1524)
				(type default)
			)
			(layer "B.SilkS")
		)
		(fp_rect
			(start 0.508 0.9398)
			(end -0.508 -0.9398)
			(stroke
				(width 0)
				(type default)
			)
			(fill no)
			(layer "B.CrtYd")
		)
		(fp_rect
			(start 0.508 0.9398)
			(end -0.508 -0.9398)
			(stroke
				(width 0)
				(type default)
			)
			(fill no)
			(layer "B.Fab")
		)
		(pad "1" smd custom
			(at 0 -0.4445 180)
			(size 0.1397 0.1397)
			(layers "B.Cu" "B.Mask" "B.Paste")
			(net "I2C_IOM_SCL")
			(options
				(clearance outline)
				(anchor circle)
			)
			(primitives
				(gr_poly
					(pts
						(arc
							(start -0.1778 0.2794)
							(mid -0.249642 0.249642)
							(end -0.2794 0.1778)
						)
						(arc
							(start -0.2794 -0.1778)
							(mid -0.249642 -0.249642)
							(end -0.1778 -0.2794)
						)
						(arc
							(start 0.1778 -0.2794)
							(mid 0.249642 -0.249642)
							(end 0.2794 -0.1778)
						)
						(arc
							(start 0.2794 0.1778)
							(mid 0.249642 0.249642)
							(end 0.1778 0.2794)
						)
					)
					(width 0)
					(fill yes)
				)
			)
		)
		(pad "2" smd custom
			(at 0 0.4445 180)
			(size 0.1397 0.1397)
			(layers "B.Cu" "B.Mask" "B.Paste")
			(net "BMC_SMB1_CLK")
			(options
				(clearance outline)
				(anchor circle)
			)
			(primitives
				(gr_poly
					(pts
						(arc
							(start -0.1778 0.2794)
							(mid -0.249642 0.249642)
							(end -0.2794 0.1778)
						)
						(arc
							(start -0.2794 -0.1778)
							(mid -0.249642 -0.249642)
							(end -0.1778 -0.2794)
						)
						(arc
							(start 0.1778 -0.2794)
							(mid 0.249642 -0.249642)
							(end 0.2794 -0.1778)
						)
						(arc
							(start 0.2794 0.1778)
							(mid 0.249642 0.249642)
							(end 0.1778 0.2794)
						)
					)
					(width 0)
					(fill yes)
				)
			)
		)
	)
)
